# T6G (Grand Teton) — schematic netlist excerpt (pin names and nets, part order shuffled) for the footprints in the layout excerpt that follows; sources: Cadence DE-HDL packaged netlist, KiCad conversion of 04192023_DAF0TMB3IC0_F0TG_MB_C_brd_V02_OCP.brd

C177  Q_CAP  10UF 25V 10% X6S  pkg C0805  page 99 : A = P12V_MEM_CPU1 ; B = GND
R3213  Q_RES  0 5% EMPTY  pkg 0402LF  page 138 : A = NCSI_BMC_TX_EN_R1 ; B = RMII_BMC_OCP_TX_EN
C437  Q_CAP  10UF 6.3V 20% X6S  pkg C0402  page 356 : A = P1V8_CPU1_RT3_1A ; B = GND

(kicad_pcb
	(version 20260206)
	(generator "pcbnew")
	(generator_version "10.0")
	(general
		(thickness 1.6)
		(legacy_teardrops no)
	)
	(paper "A4")
	(title_block
		(title "04192023_DAF0TMB3IC0_F0TG_MB_C_brd_V02_OCP.brd")
		(comment 1 "Grand Teton / footprints 6404-6406 of 8354")
	)
	(layers
		(0 "F.Cu" signal "TOP")
		(4 "In1.Cu" signal "GND")
		(6 "In2.Cu" signal "IN1")
		(8 "In3.Cu" signal "GND1")
		(10 "In4.Cu" signal "IN2")
		(12 "In5.Cu" signal "GND2")
		(14 "In6.Cu" signal "IN3")
		(16 "In7.Cu" signal "GND3")
		(18 "In8.Cu" signal "VCC")
		(20 "In9.Cu" signal "VCC1")
		(22 "In10.Cu" signal "GND4")
		(24 "In11.Cu" signal "IN4")
		(26 "In12.Cu" signal "GND5")
		(28 "In13.Cu" signal "IN5")
		(30 "In14.Cu" signal "GND6")
		(32 "In15.Cu" signal "IN6")
		(34 "In16.Cu" signal "GND7")
		(2 "B.Cu" signal "BOTTOM")
		(9 "F.Adhes" user "F.Adhesive")
		(11 "B.Adhes" user "B.Adhesive")
		(13 "F.Paste" user "Package Geometry/Pastemask Top")
		(15 "B.Paste" user "Package Geometry/Pastemask Bottom")
		(5 "F.SilkS" user "Ref Des/Silkscreen Top")
		(7 "B.SilkS" user "Ref Des/Silkscreen Bottom")
		(1 "F.Mask" user "Board Geometry/Soldermask Top")
		(3 "B.Mask" user "Board Geometry/Soldermask Bottom")
		(17 "Dwgs.User" user "User.Drawings")
		(19 "Cmts.User" user "User.Comments")
		(21 "Eco1.User" user "User.Eco1")
		(23 "Eco2.User" user "User.Eco2")
		(25 "Edge.Cuts" user "Board Geometry/Outline")
		(27 "Margin" user)
		(31 "F.CrtYd" user "Package Geometry/Place Bound Top")
		(29 "B.CrtYd" user "Package Geometry/Place Bound Bottom")
		(35 "F.Fab" user "Ref Des/Assembly Top")
		(33 "B.Fab" user "Ref Des/Assembly Bottom")
	)
	(footprint ""
		(layer "B.Cu")
		(at 124.091192 -390.560052 90)
		(property "Reference" "C437"
			(at 0 0 90)
			(layer "B.SilkS")
			(hide yes)
			(effects
				(font
					(size 1.27 1.27)
				)
				(justify mirror)
			)
		)
		(property "Value" ""
			(at 0 0 90)
			(layer "B.Fab")
			(effects
				(font
					(size 1.27 1.27)
				)
				(justify mirror)
			)
		)
		(duplicate_pad_numbers_are_jumpers no)
		(fp_line
			(start 0.7874 -0.4064)
			(end -0.7874 -0.4064)
			(stroke
				(width 0.1524)
				(type default)
			)
			(layer "B.SilkS")
		)
		(fp_line
			(start -0.7874 -0.4064)
			(end -0.7874 0.4064)
			(stroke
				(width 0.1524)
				(type default)
			)
			(layer "B.SilkS")
		)
		(fp_line
			(start 0.7874 0.4064)
			(end 0.7874 -0.4064)
			(stroke
				(width 0.1524)
				(type default)
			)
			(layer "B.SilkS")
		)
		(fp_line
			(start -0.7874 0.4064)
			(end 0.7874 0.4064)
			(stroke
				(width 0.1524)
				(type default)
			)
			(layer "B.SilkS")
		)
		(fp_line
			(start 0.67945 -0.305054)
			(end 0.12065 -0.305054)
			(stroke
				(width 0.1)
				(type default)
			)
			(layer "B.Fab")
		)
		(fp_line
			(start 0.12065 -0.305054)
			(end 0.12065 -0.2794)
			(stroke
				(width 0.1)
				(type default)
			)
			(layer "B.Fab")
		)
		(fp_line
			(start -0.12065 -0.3048)
			(end -0.67945 -0.3048)
			(stroke
				(width 0.1)
				(type default)
			)
			(layer "B.Fab")
		)
		(fp_line
			(start -0.67945 -0.3048)
			(end -0.67945 0.3048)
			(stroke
				(width 0.1)
				(type default)
			)
			(layer "B.Fab")
		)
		(fp_line
			(start 0.12065 -0.2794)
			(end -0.12065 -0.2794)
			(stroke
				(width 0.1)
				(type default)
			)
			(layer "B.Fab")
		)
		(fp_line
			(start -0.12065 -0.2794)
			(end -0.12065 -0.3048)
			(stroke
				(width 0.1)
				(type default)
			)
			(layer "B.Fab")
		)
		(fp_line
			(start 0.12065 0.2794)
			(end 0.12065 0.3048)
			(stroke
				(width 0.1)
				(type default)
			)
			(layer "B.Fab")
		)
		(fp_line
			(start -0.120396 0.2794)
			(end 0.12065 0.2794)
			(stroke
				(width 0.1)
				(type default)
			)
			(layer "B.Fab")
		)
		(fp_line
			(start 0.67945 0.3048)
			(end 0.67945 -0.305054)
			(stroke
				(width 0.1)
				(type default)
			)
			(layer "B.Fab")
		)
		(fp_line
			(start 0.12065 0.3048)
			(end 0.67945 0.3048)
			(stroke
				(width 0.1)
				(type default)
			)
			(layer "B.Fab")
		)
		(fp_line
			(start -0.120396 0.3048)
			(end -0.120396 0.2794)
			(stroke
				(width 0.1)
				(type default)
			)
			(layer "B.Fab")
		)
		(fp_line
			(start -0.67945 0.3048)
			(end -0.120396 0.3048)
			(stroke
				(width 0.1)
				(type default)
			)
			(layer "B.Fab")
		)
		(pad "1" smd circle
			(at 0.40005 0 270)
			(size 0 0)
			(layers "B.Cu" "B.Mask" "B.Paste")
			(net "P1V8_CPU1_RT3_1A")
		)
		(pad "2" smd circle
			(at -0.40005 0 270)
			(size 0 0)
			(layers "B.Cu" "B.Mask" "B.Paste")
			(net "GND")
		)
	)
	(footprint ""
		(layer "B.Cu")
		(at 191.992758 -69.443346)
		(property "Reference" "R3213"
			(at 0 0 0)
			(layer "B.SilkS")
			(hide yes)
			(effects
				(font
					(size 1.27 1.27)
				)
				(justify mirror)
			)
		)
		(property "Value" ""
			(at 0 0 0)
			(layer "B.Fab")
			(effects
				(font
					(size 1.27 1.27)
				)
				(justify mirror)
			)
		)
		(duplicate_pad_numbers_are_jumpers no)
		(fp_line
			(start -0.7874 -0.4064)
			(end -0.7874 0.4064)
			(stroke
				(width 0.1524)
				(type default)
			)
			(layer "B.SilkS")
		)
		(fp_line
			(start -0.7874 0.4064)
			(end 0.7874 0.4064)
			(stroke
				(width 0.1524)
				(type default)
			)
			(layer "B.SilkS")
		)
		(fp_line
			(start 0.7874 -0.4064)
			(end -0.7874 -0.4064)
			(stroke
				(width 0.1524)
				(type default)
			)
			(layer "B.SilkS")
		)
		(fp_line
			(start 0.7874 0.4064)
			(end 0.7874 -0.4064)
			(stroke
				(width 0.1524)
				(type default)
			)
			(layer "B.SilkS")
		)
		(fp_line
			(start -0.67945 -0.3048)
			(end -0.67945 0.3048)
			(stroke
				(width 0.1)
				(type default)
			)
			(layer "B.Fab")
		)
		(fp_line
			(start -0.67945 0.3048)
			(end -0.120396 0.3048)
			(stroke
				(width 0.1)
				(type default)
			)
			(layer "B.Fab")
		)
		(fp_line
			(start -0.12065 -0.3048)
			(end -0.67945 -0.3048)
			(stroke
				(width 0.1)
				(type default)
			)
			(layer "B.Fab")
		)
		(fp_line
			(start -0.12065 -0.2794)
			(end -0.12065 -0.3048)
			(stroke
				(width 0.1)
				(type default)
			)
			(layer "B.Fab")
		)
		(fp_line
			(start -0.120396 0.2794)
			(end 0.12065 0.2794)
			(stroke
				(width 0.1)
				(type default)
			)
			(layer "B.Fab")
		)
		(fp_line
			(start -0.120396 0.3048)
			(end -0.120396 0.2794)
			(stroke
				(width 0.1)
				(type default)
			)
			(layer "B.Fab")
		)
		(fp_line
			(start 0.12065 -0.305054)
			(end 0.12065 -0.2794)
			(stroke
				(width 0.1)
				(type default)
			)
			(layer "B.Fab")
		)
		(fp_line
			(start 0.12065 -0.2794)
			(end -0.12065 -0.2794)
			(stroke
				(width 0.1)
				(type default)
			)
			(layer "B.Fab")
		)
		(fp_line
			(start 0.12065 0.2794)
			(end 0.12065 0.3048)
			(stroke
				(width 0.1)
				(type default)
			)
			(layer "B.Fab")
		)
		(fp_line
			(start 0.12065 0.3048)
			(end 0.67945 0.3048)
			(stroke
				(width 0.1)
				(type default)
			)
			(layer "B.Fab")
		)
		(fp_line
			(start 0.67945 -0.305054)
			(end 0.12065 -0.305054)
			(stroke
				(width 0.1)
				(type default)
			)
			(layer "B.Fab")
		)
		(fp_line
			(start 0.67945 0.3048)
			(end 0.67945 -0.305054)
			(stroke
				(width 0.1)
				(type default)
			)
			(layer "B.Fab")
		)
		(pad "1" smd circle
			(at 0.40005 0 180)
			(size 0 0)
			(layers "B.Cu" "B.Mask" "B.Paste")
			(net "NCSI_BMC_TX_EN_R1")
		)
		(pad "2" smd circle
			(at -0.40005 0 180)
			(size 0 0)
			(layers "B.Cu" "B.Mask" "B.Paste")
			(net "RMII_BMC_OCP_TX_EN")
		)
	)
	(footprint ""
		(layer "B.Cu")
		(at 51.884072 -192.66027)
		(property "Reference" "C177"
			(at 0 0 0)
			(layer "B.SilkS")
			(hide yes)
			(effects
				(font
					(size 1.27 1.27)
				)
				(justify mirror)
			)
		)
		(property "Value" ""
			(at 0 0 0)
			(layer "B.Fab")
			(effects
				(font
					(size 1.27 1.27)
				)
				(justify mirror)
			)
		)
		(duplicate_pad_numbers_are_jumpers no)
		(fp_line
			(start -1.524 -0.762)
			(end -1.524 0.762)
			(stroke
				(width 0.1524)
				(type default)
			)
			(layer "B.SilkS")
		)
		(fp_line
			(start -1.524 0.762)
			(end 1.524 0.762)
			(stroke
				(width 0.1524)
				(type default)
			)
			(layer "B.SilkS")
		)
		(fp_line
			(start 1.524 -0.762)
			(end -1.524 -0.762)
			(stroke
				(width 0.1524)
				(type default)
			)
			(layer "B.SilkS")
		)
		(fp_line
			(start 1.524 0.762)
			(end 1.524 -0.762)
			(stroke
				(width 0.1524)
				(type default)
			)
			(layer "B.SilkS")
		)
		(fp_line
			(start -1.1049 -0.724916)
			(end 1.1049 -0.724916)
			(stroke
				(width 0.1)
				(type default)
			)
			(layer "B.Fab")
		)
		(fp_line
			(start -1.1049 0.724916)
			(end -1.1049 -0.724916)
			(stroke
				(width 0.1)
				(type default)
			)
			(layer "B.Fab")
		)
		(fp_line
			(start 1.1049 -0.724916)
			(end 1.1049 0.724916)
			(stroke
				(width 0.1)
				(type default)
			)
			(layer "B.Fab")
		)
		(fp_line
			(start 1.1049 0.724916)
			(end -1.1049 0.724916)
			(stroke
				(width 0.1)
				(type default)
			)
			(layer "B.Fab")
		)
		(pad "1" smd rect
			(at 0.889 0)
			(size 1.016 1.27)
			(layers "B.Cu" "B.Mask" "B.Paste")
			(net "P12V_MEM_CPU1")
		)
		(pad "2" smd rect
			(at -0.889 0)
			(size 1.016 1.27)
			(layers "B.Cu" "B.Mask" "B.Paste")
			(net "GND")
		)
	)
)
